(kicad_pcb
	(version 20260206)
	(generator "pcbnew")
	(generator_version "10.0")
	(general
		(thickness 1.6)
		(legacy_teardrops no)
	)
	(paper "A4")
	(title_block
		(title "03242023_DA0F0TMBIJ0_F0T_Motherboard_J_brd_V01_OCP.brd")
		(comment 1 "Grand Teton / footprints 2628-2634 of 6105")
	)
	(layers
		(0 "F.Cu" signal "TOP")
		(4 "In1.Cu" signal "GND")
		(6 "In2.Cu" signal "IN1")
		(8 "In3.Cu" signal "GND1")
		(10 "In4.Cu" signal "IN2")
		(12 "In5.Cu" signal "GND2")
		(14 "In6.Cu" signal "IN3")
		(16 "In7.Cu" signal "GND3")
		(18 "In8.Cu" signal "VCC")
		(20 "In9.Cu" signal "VCC1")
		(22 "In10.Cu" signal "GND4")
		(24 "In11.Cu" signal "IN4")
		(26 "In12.Cu" signal "GND5")
		(28 "In13.Cu" signal "IN5")
		(30 "In14.Cu" signal "GND6")
		(32 "In15.Cu" signal "IN6")
		(34 "In16.Cu" signal "GND7")
		(2 "B.Cu" signal "BOTTOM")
		(9 "F.Adhes" user "F.Adhesive")
		(11 "B.Adhes" user "B.Adhesive")
		(13 "F.Paste" user "Package Geometry/Pastemask Top")
		(15 "B.Paste" user "Package Geometry/Pastemask Bottom")
		(5 "F.SilkS" user "Ref Des/Silkscreen Top")
		(7 "B.SilkS" user "Ref Des/Silkscreen Bottom")
		(1 "F.Mask" user "Board Geometry/Soldermask Top")
		(3 "B.Mask" user "Board Geometry/Soldermask Bottom")
		(17 "Dwgs.User" user "User.Drawings")
		(19 "Cmts.User" user "User.Comments")
		(21 "Eco1.User" user "User.Eco1")
		(23 "Eco2.User" user "User.Eco2")
		(25 "Edge.Cuts" user "Board Geometry/Outline")
		(27 "Margin" user)
		(31 "F.CrtYd" user "Package Geometry/Place Bound Top")
		(29 "B.CrtYd" user "Package Geometry/Place Bound Bottom")
		(35 "F.Fab" user "Ref Des/Assembly Top")
		(33 "B.Fab" user "Ref Des/Assembly Bottom")
	)
	(footprint ""
		(layer "F.Cu")
		(at 495.599212 -342.797638)
		(property "Reference" "DB1"
			(at 2.19837 2.397506 90)
			(unlocked yes)
			(layer "F.SilkS")
			(effects
				(font
					(size 0.7874 0.5842)
					(thickness 0.1524)
				)
				(justify left)
			)
		)
		(property "Value" ""
			(at 0 0 0)
			(layer "F.Fab")
			(effects
				(font
					(size 1.27 1.27)
				)
			)
		)
		(duplicate_pad_numbers_are_jumpers no)
		(fp_line
			(start -3.330702 -4.771136)
			(end 3.330702 -4.771136)
			(stroke
				(width 0.1524)
				(type default)
			)
			(layer "F.SilkS")
		)
		(fp_line
			(start 0 4.011168)
			(end -3.330702 -4.771136)
			(stroke
				(width 0.1524)
				(type default)
			)
			(layer "F.SilkS")
		)
		(fp_line
			(start 3.330702 -4.771136)
			(end 0 4.011168)
			(stroke
				(width 0.1524)
				(type default)
			)
			(layer "F.SilkS")
		)
		(fp_line
			(start -3.330702 -4.771136)
			(end 3.330702 -4.771136)
			(stroke
				(width 0.1)
				(type default)
			)
			(layer "F.Fab")
		)
		(fp_line
			(start 0 4.011168)
			(end -3.330702 -4.771136)
			(stroke
				(width 0.1)
				(type default)
			)
			(layer "F.Fab")
		)
		(fp_line
			(start 3.330702 -4.771136)
			(end 0 4.011168)
			(stroke
				(width 0.1)
				(type default)
			)
			(layer "F.Fab")
		)
		(pad "1" thru_hole circle
			(at 0 0)
			(size 2.159 2.159)
			(drill 1.7018)
			(layers "*.Cu" "*.Mask")
			(remove_unused_layers no)
			(net "T1_GND")
			(clearance 0.0254)
			(thermal_gap 0.0254)
		)
		(pad "2" thru_hole circle
			(at -1.27 -3.348736)
			(size 2.159 2.159)
			(drill 1.7018)
			(layers "*.Cu" "*.Mask")
			(remove_unused_layers no)
			(net "TDR_SE_40_OHM_TOP")
			(clearance 0.0254)
			(thermal_gap 0.0254)
		)
		(pad "3" thru_hole circle
			(at 1.27 -3.348736)
			(size 2.159 2.159)
			(drill 1.7018)
			(layers "*.Cu" "*.Mask")
			(remove_unused_layers no)
			(net "TDR_SE_40_OHM_TOP")
			(clearance 0.0254)
			(thermal_gap 0.0254)
		)
	)
	(footprint ""
		(layer "F.Cu")
		(at 398.397984 -17.612614 90)
		(property "Reference" "C844"
			(at 0 0 90)
			(layer "F.SilkS")
			(hide yes)
			(effects
				(font
					(size 1.27 1.27)
				)
			)
		)
		(property "Value" ""
			(at 0 0 90)
			(layer "F.Fab")
			(effects
				(font
					(size 1.27 1.27)
				)
			)
		)
		(duplicate_pad_numbers_are_jumpers no)
		(fp_line
			(start 0.299974 -0.150114)
			(end 0.299974 0.150114)
			(stroke
				(width 0.1)
				(type default)
			)
			(layer "F.Fab")
		)
		(fp_line
			(start -0.299974 -0.150114)
			(end 0.299974 -0.150114)
			(stroke
				(width 0.1)
				(type default)
			)
			(layer "F.Fab")
		)
		(fp_line
			(start 0.299974 0.150114)
			(end -0.299974 0.150114)
			(stroke
				(width 0.1)
				(type default)
			)
			(layer "F.Fab")
		)
		(fp_line
			(start -0.299974 0.150114)
			(end -0.299974 -0.150114)
			(stroke
				(width 0.1)
				(type default)
			)
			(layer "F.Fab")
		)
		(pad "1" smd rect
			(at -0.2667 0 90)
			(size 0.3048 0.381)
			(layers "F.Cu" "F.Mask" "F.Paste")
			(net "P5E_CPU0_PE1_TX_C_DN<12>")
		)
		(pad "2" smd rect
			(at 0.2667 0 90)
			(size 0.3048 0.381)
			(layers "F.Cu" "F.Mask" "F.Paste")
			(net "P5E_CPU0_PE1_TX_DN<12>")
		)
	)
	(footprint ""
		(layer "F.Cu")
		(at 449.044314 -25.10028 -90)
		(property "Reference" "PC2079"
			(at 0 0 270)
			(layer "F.SilkS")
			(hide yes)
			(effects
				(font
					(size 1.27 1.27)
				)
			)
		)
		(property "Value" ""
			(at 0 0 270)
			(layer "F.Fab")
			(effects
				(font
					(size 1.27 1.27)
				)
			)
		)
		(duplicate_pad_numbers_are_jumpers no)
		(fp_line
			(start -0.7874 0.4064)
			(end -0.7874 -0.4064)
			(stroke
				(width 0.1524)
				(type default)
			)
			(layer "F.SilkS")
		)
		(fp_line
			(start 0.7874 0.4064)
			(end -0.7874 0.4064)
			(stroke
				(width 0.1524)
				(type default)
			)
			(layer "F.SilkS")
		)
		(fp_line
			(start -0.7874 -0.4064)
			(end 0.7874 -0.4064)
			(stroke
				(width 0.1524)
				(type default)
			)
			(layer "F.SilkS")
		)
		(fp_line
			(start 0.7874 -0.4064)
			(end 0.7874 0.4064)
			(stroke
				(width 0.1524)
				(type default)
			)
			(layer "F.SilkS")
		)
		(fp_line
			(start -0.67945 0.3048)
			(end -0.67945 -0.305054)
			(stroke
				(width 0.1)
				(type default)
			)
			(layer "F.Fab")
		)
		(fp_line
			(start -0.12065 0.3048)
			(end -0.67945 0.3048)
			(stroke
				(width 0.1)
				(type default)
			)
			(layer "F.Fab")
		)
		(fp_line
			(start 0.120396 0.3048)
			(end 0.120396 0.2794)
			(stroke
				(width 0.1)
				(type default)
			)
			(layer "F.Fab")
		)
		(fp_line
			(start 0.67945 0.3048)
			(end 0.120396 0.3048)
			(stroke
				(width 0.1)
				(type default)
			)
			(layer "F.Fab")
		)
		(fp_line
			(start -0.12065 0.2794)
			(end -0.12065 0.3048)
			(stroke
				(width 0.1)
				(type default)
			)
			(layer "F.Fab")
		)
		(fp_line
			(start 0.120396 0.2794)
			(end -0.12065 0.2794)
			(stroke
				(width 0.1)
				(type default)
			)
			(layer "F.Fab")
		)
		(fp_line
			(start -0.12065 -0.2794)
			(end 0.12065 -0.2794)
			(stroke
				(width 0.1)
				(type default)
			)
			(layer "F.Fab")
		)
		(fp_line
			(start 0.12065 -0.2794)
			(end 0.12065 -0.3048)
			(stroke
				(width 0.1)
				(type default)
			)
			(layer "F.Fab")
		)
		(fp_line
			(start 0.12065 -0.3048)
			(end 0.67945 -0.3048)
			(stroke
				(width 0.1)
				(type default)
			)
			(layer "F.Fab")
		)
		(fp_line
			(start 0.67945 -0.3048)
			(end 0.67945 0.3048)
			(stroke
				(width 0.1)
				(type default)
			)
			(layer "F.Fab")
		)
		(fp_line
			(start -0.67945 -0.305054)
			(end -0.12065 -0.305054)
			(stroke
				(width 0.1)
				(type default)
			)
			(layer "F.Fab")
		)
		(fp_line
			(start -0.12065 -0.305054)
			(end -0.12065 -0.2794)
			(stroke
				(width 0.1)
				(type default)
			)
			(layer "F.Fab")
		)
		(pad "1" smd circle
			(at -0.40005 0 270)
			(size 0 0)
			(layers "F.Cu" "F.Mask" "F.Paste")
			(net "P12V_AUX")
		)
		(pad "2" smd circle
			(at 0.40005 0 270)
			(size 0 0)
			(layers "F.Cu" "F.Mask" "F.Paste")
			(net "GND")
		)
	)
	(footprint ""
		(layer "F.Cu")
		(at 151.844756 -65.413128)
		(property "Reference" "R3775"
			(at 0 0 0)
			(layer "F.SilkS")
			(hide yes)
			(effects
				(font
					(size 1.27 1.27)
				)
			)
		)
		(property "Value" ""
			(at 0 0 0)
			(layer "F.Fab")
			(effects
				(font
					(size 1.27 1.27)
				)
			)
		)
		(duplicate_pad_numbers_are_jumpers no)
		(fp_line
			(start -0.7874 -0.4064)
			(end 0.7874 -0.4064)
			(stroke
				(width 0.1524)
				(type default)
			)
			(layer "F.SilkS")
		)
		(fp_line
			(start -0.7874 0.4064)
			(end -0.7874 -0.4064)
			(stroke
				(width 0.1524)
				(type default)
			)
			(layer "F.SilkS")
		)
		(fp_line
			(start 0.7874 -0.4064)
			(end 0.7874 0.4064)
			(stroke
				(width 0.1524)
				(type default)
			)
			(layer "F.SilkS")
		)
		(fp_line
			(start 0.7874 0.4064)
			(end -0.7874 0.4064)
			(stroke
				(width 0.1524)
				(type default)
			)
			(layer "F.SilkS")
		)
		(fp_line
			(start -0.67945 -0.305054)
			(end -0.12065 -0.305054)
			(stroke
				(width 0.1)
				(type default)
			)
			(layer "F.Fab")
		)
		(fp_line
			(start -0.67945 0.3048)
			(end -0.67945 -0.305054)
			(stroke
				(width 0.1)
				(type default)
			)
			(layer "F.Fab")
		)
		(fp_line
			(start -0.12065 -0.305054)
			(end -0.12065 -0.2794)
			(stroke
				(width 0.1)
				(type default)
			)
			(layer "F.Fab")
		)
		(fp_line
			(start -0.12065 -0.2794)
			(end 0.12065 -0.2794)
			(stroke
				(width 0.1)
				(type default)
			)
			(layer "F.Fab")
		)
		(fp_line
			(start -0.12065 0.2794)
			(end -0.12065 0.3048)
			(stroke
				(width 0.1)
				(type default)
			)
			(layer "F.Fab")
		)
		(fp_line
			(start -0.12065 0.3048)
			(end -0.67945 0.3048)
			(stroke
				(width 0.1)
				(type default)
			)
			(layer "F.Fab")
		)
		(fp_line
			(start 0.120396 0.2794)
			(end -0.12065 0.2794)
			(stroke
				(width 0.1)
				(type default)
			)
			(layer "F.Fab")
		)
		(fp_line
			(start 0.120396 0.3048)
			(end 0.120396 0.2794)
			(stroke
				(width 0.1)
				(type default)
			)
			(layer "F.Fab")
		)
		(fp_line
			(start 0.12065 -0.3048)
			(end 0.67945 -0.3048)
			(stroke
				(width 0.1)
				(type default)
			)
			(layer "F.Fab")
		)
		(fp_line
			(start 0.12065 -0.2794)
			(end 0.12065 -0.3048)
			(stroke
				(width 0.1)
				(type default)
			)
			(layer "F.Fab")
		)
		(fp_line
			(start 0.67945 -0.3048)
			(end 0.67945 0.3048)
			(stroke
				(width 0.1)
				(type default)
			)
			(layer "F.Fab")
		)
		(fp_line
			(start 0.67945 0.3048)
			(end 0.120396 0.3048)
			(stroke
				(width 0.1)
				(type default)
			)
			(layer "F.Fab")
		)
		(pad "1" smd circle
			(at -0.40005 0)
			(size 0 0)
			(layers "F.Cu" "F.Mask" "F.Paste")
			(net "RST_SMB_SWITCH_N")
		)
		(pad "2" smd circle
			(at 0.40005 0)
			(size 0 0)
			(layers "F.Cu" "F.Mask" "F.Paste")
			(net "RST_SMB_E1S_N")
		)
	)
	(footprint ""
		(layer "F.Cu")
		(at 460.523844 -70.271386 -90)
		(property "Reference" "PC2263"
			(at 0 0 270)
			(layer "F.SilkS")
			(hide yes)
			(effects
				(font
					(size 1.27 1.27)
				)
			)
		)
		(property "Value" ""
			(at 0 0 270)
			(layer "F.Fab")
			(effects
				(font
					(size 1.27 1.27)
				)
			)
		)
		(duplicate_pad_numbers_are_jumpers no)
		(fp_line
			(start -1.524 0.762)
			(end -1.524 -0.762)
			(stroke
				(width 0.1524)
				(type default)
			)
			(layer "F.SilkS")
		)
		(fp_line
			(start 1.524 0.762)
			(end -1.524 0.762)
			(stroke
				(width 0.1524)
				(type default)
			)
			(layer "F.SilkS")
		)
		(fp_line
			(start -1.524 -0.762)
			(end 1.524 -0.762)
			(stroke
				(width 0.1524)
				(type default)
			)
			(layer "F.SilkS")
		)
		(fp_line
			(start 1.524 -0.762)
			(end 1.524 0.762)
			(stroke
				(width 0.1524)
				(type default)
			)
			(layer "F.SilkS")
		)
		(fp_line
			(start -1.1049 0.724916)
			(end 1.1049 0.724916)
			(stroke
				(width 0.1)
				(type default)
			)
			(layer "F.Fab")
		)
		(fp_line
			(start 1.1049 0.724916)
			(end 1.1049 -0.724916)
			(stroke
				(width 0.1)
				(type default)
			)
			(layer "F.Fab")
		)
		(fp_line
			(start -1.1049 -0.724916)
			(end -1.1049 0.724916)
			(stroke
				(width 0.1)
				(type default)
			)
			(layer "F.Fab")
		)
		(fp_line
			(start 1.1049 -0.724916)
			(end -1.1049 -0.724916)
			(stroke
				(width 0.1)
				(type default)
			)
			(layer "F.Fab")
		)
		(pad "1" smd rect
			(at -0.889 0 90)
			(size 1.016 1.27)
			(layers "F.Cu" "F.Mask" "F.Paste")
			(net "SW_P3V3_AUX_FLT")
		)
		(pad "2" smd rect
			(at 0.889 0 90)
			(size 1.016 1.27)
			(layers "F.Cu" "F.Mask" "F.Paste")
			(net "GND")
		)
	)
	(footprint ""
		(layer "F.Cu")
		(at 308.00294 -56.045608 90)
		(property "Reference" "R149"
			(at 0 0 90)
			(layer "F.SilkS")
			(hide yes)
			(effects
				(font
					(size 1.27 1.27)
				)
			)
		)
		(property "Value" ""
			(at 0 0 90)
			(layer "F.Fab")
			(effects
				(font
					(size 1.27 1.27)
				)
			)
		)
		(duplicate_pad_numbers_are_jumpers no)
		(fp_line
			(start 0.7874 -0.4064)
			(end 0.7874 0.4064)
			(stroke
				(width 0.1524)
				(type default)
			)
			(layer "F.SilkS")
		)
		(fp_line
			(start -0.7874 -0.4064)
			(end 0.7874 -0.4064)
			(stroke
				(width 0.1524)
				(type default)
			)
			(layer "F.SilkS")
		)
		(fp_line
			(start 0.7874 0.4064)
			(end -0.7874 0.4064)
			(stroke
				(width 0.1524)
				(type default)
			)
			(layer "F.SilkS")
		)
		(fp_line
			(start -0.7874 0.4064)
			(end -0.7874 -0.4064)
			(stroke
				(width 0.1524)
				(type default)
			)
			(layer "F.SilkS")
		)
		(fp_line
			(start -0.12065 -0.305054)
			(end -0.12065 -0.2794)
			(stroke
				(width 0.1)
				(type default)
			)
			(layer "F.Fab")
		)
		(fp_line
			(start -0.67945 -0.305054)
			(end -0.12065 -0.305054)
			(stroke
				(width 0.1)
				(type default)
			)
			(layer "F.Fab")
		)
		(fp_line
			(start 0.67945 -0.3048)
			(end 0.67945 0.3048)
			(stroke
				(width 0.1)
				(type default)
			)
			(layer "F.Fab")
		)
		(fp_line
			(start 0.12065 -0.3048)
			(end 0.67945 -0.3048)
			(stroke
				(width 0.1)
				(type default)
			)
			(layer "F.Fab")
		)
		(fp_line
			(start 0.12065 -0.2794)
			(end 0.12065 -0.3048)
			(stroke
				(width 0.1)
				(type default)
			)
			(layer "F.Fab")
		)
		(fp_line
			(start -0.12065 -0.2794)
			(end 0.12065 -0.2794)
			(stroke
				(width 0.1)
				(type default)
			)
			(layer "F.Fab")
		)
		(fp_line
			(start 0.120396 0.2794)
			(end -0.12065 0.2794)
			(stroke
				(width 0.1)
				(type default)
			)
			(layer "F.Fab")
		)
		(fp_line
			(start -0.12065 0.2794)
			(end -0.12065 0.3048)
			(stroke
				(width 0.1)
				(type default)
			)
			(layer "F.Fab")
		)
		(fp_line
			(start 0.67945 0.3048)
			(end 0.120396 0.3048)
			(stroke
				(width 0.1)
				(type default)
			)
			(layer "F.Fab")
		)
		(fp_line
			(start 0.120396 0.3048)
			(end 0.120396 0.2794)
			(stroke
				(width 0.1)
				(type default)
			)
			(layer "F.Fab")
		)
		(fp_line
			(start -0.12065 0.3048)
			(end -0.67945 0.3048)
			(stroke
				(width 0.1)
				(type default)
			)
			(layer "F.Fab")
		)
		(fp_line
			(start -0.67945 0.3048)
			(end -0.67945 -0.305054)
			(stroke
				(width 0.1)
				(type default)
			)
			(layer "F.Fab")
		)
		(pad "1" smd circle
			(at -0.40005 0 90)
			(size 0 0)
			(layers "F.Cu" "F.Mask" "F.Paste")
			(net "PECI_PCH_R")
		)
		(pad "2" smd circle
			(at 0.40005 0 90)
			(size 0 0)
			(layers "F.Cu" "F.Mask" "F.Paste")
			(net "PECI_PCH_B1")
		)
	)
	(footprint ""
		(layer "F.Cu")
		(at 15.436596 -396.263876)
		(property "Reference" "R3271"
			(at 0 0 0)
			(layer "F.SilkS")
			(hide yes)
			(effects
				(font
					(size 1.27 1.27)
				)
			)
		)
		(property "Value" ""
			(at 0 0 0)
			(layer "F.Fab")
			(effects
				(font
					(size 1.27 1.27)
				)
			)
		)
		(duplicate_pad_numbers_are_jumpers no)
		(fp_line
			(start -0.7874 -0.4064)
			(end 0.7874 -0.4064)
			(stroke
				(width 0.1524)
				(type default)
			)
			(layer "F.SilkS")
		)
		(fp_line
			(start -0.7874 0.4064)
			(end -0.7874 -0.4064)
			(stroke
				(width 0.1524)
				(type default)
			)
			(layer "F.SilkS")
		)
		(fp_line
			(start 0.7874 -0.4064)
			(end 0.7874 0.4064)
			(stroke
				(width 0.1524)
				(type default)
			)
			(layer "F.SilkS")
		)
		(fp_line
			(start 0.7874 0.4064)
			(end -0.7874 0.4064)
			(stroke
				(width 0.1524)
				(type default)
			)
			(layer "F.SilkS")
		)
		(fp_line
			(start -0.67945 -0.305054)
			(end -0.12065 -0.305054)
			(stroke
				(width 0.1)
				(type default)
			)
			(layer "F.Fab")
		)
		(fp_line
			(start -0.67945 0.3048)
			(end -0.67945 -0.305054)
			(stroke
				(width 0.1)
				(type default)
			)
			(layer "F.Fab")
		)
		(fp_line
			(start -0.12065 -0.305054)
			(end -0.12065 -0.2794)
			(stroke
				(width 0.1)
				(type default)
			)
			(layer "F.Fab")
		)
		(fp_line
			(start -0.12065 -0.2794)
			(end 0.12065 -0.2794)
			(stroke
				(width 0.1)
				(type default)
			)
			(layer "F.Fab")
		)
		(fp_line
			(start -0.12065 0.2794)
			(end -0.12065 0.3048)
			(stroke
				(width 0.1)
				(type default)
			)
			(layer "F.Fab")
		)
		(fp_line
			(start -0.12065 0.3048)
			(end -0.67945 0.3048)
			(stroke
				(width 0.1)
				(type default)
			)
			(layer "F.Fab")
		)
		(fp_line
			(start 0.120396 0.2794)
			(end -0.12065 0.2794)
			(stroke
				(width 0.1)
				(type default)
			)
			(layer "F.Fab")
		)
		(fp_line
			(start 0.120396 0.3048)
			(end 0.120396 0.2794)
			(stroke
				(width 0.1)
				(type default)
			)
			(layer "F.Fab")
		)
		(fp_line
			(start 0.12065 -0.3048)
			(end 0.67945 -0.3048)
			(stroke
				(width 0.1)
				(type default)
			)
			(layer "F.Fab")
		)
		(fp_line
			(start 0.12065 -0.2794)
			(end 0.12065 -0.3048)
			(stroke
				(width 0.1)
				(type default)
			)
			(layer "F.Fab")
		)
		(fp_line
			(start 0.67945 -0.3048)
			(end 0.67945 0.3048)
			(stroke
				(width 0.1)
				(type default)
			)
			(layer "F.Fab")
		)
		(fp_line
			(start 0.67945 0.3048)
			(end 0.120396 0.3048)
			(stroke
				(width 0.1)
				(type default)
			)
			(layer "F.Fab")
		)
		(pad "1" smd circle
			(at -0.40005 0)
			(size 0 0)
			(layers "F.Cu" "F.Mask" "F.Paste")
			(net "P3V3_AUX")
		)
		(pad "2" smd circle
			(at 0.40005 0)
			(size 0 0)
			(layers "F.Cu" "F.Mask" "F.Paste")
			(net "FM_P2E_EQA1")
		)
	)
)
